# T6G (Grand Teton) — schematic netlist excerpt (pin names and nets, part order shuffled) for the footprints in the layout excerpt that follows; sources: Cadence DE-HDL packaged netlist, KiCad conversion of 04192023_DAF0TMB3IC0_F0TG_MB_C_brd_V02_OCP.brd

PR111  Q_RES  0 5% CHIP  pkg 0402LF  page 206 : A = PVDDIO_P0_VOS3 ; B = PVDDIO_P0
R2418  Q_RES  33.2 1% CHIP  pkg 0402LF  page 150 : A = SMB_HOST_CLK_3V3AUX_SDA ; B = SMB_HOST_CLK_3V3AUX_SDA_R0
C631  Q_CAP  0.1UF 10V 10% X7S  pkg C0201  page 290 : A = P0V9_CPU0_RT1_2A ; B = GND

(kicad_pcb
	(version 20260206)
	(generator "pcbnew")
	(generator_version "10.0")
	(general
		(thickness 1.6)
		(legacy_teardrops no)
	)
	(paper "A4")
	(title_block
		(title "04192023_DAF0TMB3IC0_F0TG_MB_C_brd_V02_OCP.brd")
		(comment 1 "Grand Teton / footprints 8164-8166 of 8354")
	)
	(layers
		(0 "F.Cu" signal "TOP")
		(4 "In1.Cu" signal "GND")
		(6 "In2.Cu" signal "IN1")
		(8 "In3.Cu" signal "GND1")
		(10 "In4.Cu" signal "IN2")
		(12 "In5.Cu" signal "GND2")
		(14 "In6.Cu" signal "IN3")
		(16 "In7.Cu" signal "GND3")
		(18 "In8.Cu" signal "VCC")
		(20 "In9.Cu" signal "VCC1")
		(22 "In10.Cu" signal "GND4")
		(24 "In11.Cu" signal "IN4")
		(26 "In12.Cu" signal "GND5")
		(28 "In13.Cu" signal "IN5")
		(30 "In14.Cu" signal "GND6")
		(32 "In15.Cu" signal "IN6")
		(34 "In16.Cu" signal "GND7")
		(2 "B.Cu" signal "BOTTOM")
		(9 "F.Adhes" user "F.Adhesive")
		(11 "B.Adhes" user "B.Adhesive")
		(13 "F.Paste" user "Package Geometry/Pastemask Top")
		(15 "B.Paste" user "Package Geometry/Pastemask Bottom")
		(5 "F.SilkS" user "Ref Des/Silkscreen Top")
		(7 "B.SilkS" user "Ref Des/Silkscreen Bottom")
		(1 "F.Mask" user "Board Geometry/Soldermask Top")
		(3 "B.Mask" user "Board Geometry/Soldermask Bottom")
		(17 "Dwgs.User" user "User.Drawings")
		(19 "Cmts.User" user "User.Comments")
		(21 "Eco1.User" user "User.Eco1")
		(23 "Eco2.User" user "User.Eco2")
		(25 "Edge.Cuts" user "Board Geometry/Outline")
		(27 "Margin" user)
		(31 "F.CrtYd" user "Package Geometry/Place Bound Top")
		(29 "B.CrtYd" user "Package Geometry/Place Bound Bottom")
		(35 "F.Fab" user "Ref Des/Assembly Top")
		(33 "B.Fab" user "Ref Des/Assembly Bottom")
	)
	(footprint ""
		(layer "B.Cu")
		(at 149.884638 -13.762228 90)
		(property "Reference" "R2418"
			(at 0 0 90)
			(layer "B.SilkS")
			(hide yes)
			(effects
				(font
					(size 1.27 1.27)
				)
				(justify mirror)
			)
		)
		(property "Value" ""
			(at 0 0 90)
			(layer "B.Fab")
			(effects
				(font
					(size 1.27 1.27)
				)
				(justify mirror)
			)
		)
		(duplicate_pad_numbers_are_jumpers no)
		(fp_line
			(start 0.7874 -0.4064)
			(end -0.7874 -0.4064)
			(stroke
				(width 0.1524)
				(type default)
			)
			(layer "B.SilkS")
		)
		(fp_line
			(start -0.7874 -0.4064)
			(end -0.7874 0.4064)
			(stroke
				(width 0.1524)
				(type default)
			)
			(layer "B.SilkS")
		)
		(fp_line
			(start 0.7874 0.4064)
			(end 0.7874 -0.4064)
			(stroke
				(width 0.1524)
				(type default)
			)
			(layer "B.SilkS")
		)
		(fp_line
			(start -0.7874 0.4064)
			(end 0.7874 0.4064)
			(stroke
				(width 0.1524)
				(type default)
			)
			(layer "B.SilkS")
		)
		(fp_line
			(start 0.67945 -0.305054)
			(end 0.12065 -0.305054)
			(stroke
				(width 0.1)
				(type default)
			)
			(layer "B.Fab")
		)
		(fp_line
			(start 0.12065 -0.305054)
			(end 0.12065 -0.2794)
			(stroke
				(width 0.1)
				(type default)
			)
			(layer "B.Fab")
		)
		(fp_line
			(start -0.12065 -0.3048)
			(end -0.67945 -0.3048)
			(stroke
				(width 0.1)
				(type default)
			)
			(layer "B.Fab")
		)
		(fp_line
			(start -0.67945 -0.3048)
			(end -0.67945 0.3048)
			(stroke
				(width 0.1)
				(type default)
			)
			(layer "B.Fab")
		)
		(fp_line
			(start 0.12065 -0.2794)
			(end -0.12065 -0.2794)
			(stroke
				(width 0.1)
				(type default)
			)
			(layer "B.Fab")
		)
		(fp_line
			(start -0.12065 -0.2794)
			(end -0.12065 -0.3048)
			(stroke
				(width 0.1)
				(type default)
			)
			(layer "B.Fab")
		)
		(fp_line
			(start 0.12065 0.2794)
			(end 0.12065 0.3048)
			(stroke
				(width 0.1)
				(type default)
			)
			(layer "B.Fab")
		)
		(fp_line
			(start -0.120396 0.2794)
			(end 0.12065 0.2794)
			(stroke
				(width 0.1)
				(type default)
			)
			(layer "B.Fab")
		)
		(fp_line
			(start 0.67945 0.3048)
			(end 0.67945 -0.305054)
			(stroke
				(width 0.1)
				(type default)
			)
			(layer "B.Fab")
		)
		(fp_line
			(start 0.12065 0.3048)
			(end 0.67945 0.3048)
			(stroke
				(width 0.1)
				(type default)
			)
			(layer "B.Fab")
		)
		(fp_line
			(start -0.120396 0.3048)
			(end -0.120396 0.2794)
			(stroke
				(width 0.1)
				(type default)
			)
			(layer "B.Fab")
		)
		(fp_line
			(start -0.67945 0.3048)
			(end -0.120396 0.3048)
			(stroke
				(width 0.1)
				(type default)
			)
			(layer "B.Fab")
		)
		(pad "1" smd circle
			(at 0.40005 0 270)
			(size 0 0)
			(layers "B.Cu" "B.Mask" "B.Paste")
			(net "SMB_HOST_CLK_3V3AUX_SDA")
		)
		(pad "2" smd circle
			(at -0.40005 0 270)
			(size 0 0)
			(layers "B.Cu" "B.Mask" "B.Paste")
			(net "SMB_HOST_CLK_3V3AUX_SDA_R0")
		)
	)
	(footprint ""
		(layer "B.Cu")
		(at 280.041096 -349.381572 -90)
		(property "Reference" "PR111"
			(at 0 0 90)
			(layer "B.SilkS")
			(hide yes)
			(effects
				(font
					(size 1.27 1.27)
				)
				(justify mirror)
			)
		)
		(property "Value" ""
			(at 0 0 90)
			(layer "B.Fab")
			(effects
				(font
					(size 1.27 1.27)
				)
				(justify mirror)
			)
		)
		(duplicate_pad_numbers_are_jumpers no)
		(fp_line
			(start -0.7874 0.4064)
			(end 0.7874 0.4064)
			(stroke
				(width 0.1524)
				(type default)
			)
			(layer "B.SilkS")
		)
		(fp_line
			(start 0.7874 0.4064)
			(end 0.7874 -0.4064)
			(stroke
				(width 0.1524)
				(type default)
			)
			(layer "B.SilkS")
		)
		(fp_line
			(start -0.7874 -0.4064)
			(end -0.7874 0.4064)
			(stroke
				(width 0.1524)
				(type default)
			)
			(layer "B.SilkS")
		)
		(fp_line
			(start 0.7874 -0.4064)
			(end -0.7874 -0.4064)
			(stroke
				(width 0.1524)
				(type default)
			)
			(layer "B.SilkS")
		)
		(fp_line
			(start -0.67945 0.3048)
			(end -0.120396 0.3048)
			(stroke
				(width 0.1)
				(type default)
			)
			(layer "B.Fab")
		)
		(fp_line
			(start -0.120396 0.3048)
			(end -0.120396 0.2794)
			(stroke
				(width 0.1)
				(type default)
			)
			(layer "B.Fab")
		)
		(fp_line
			(start 0.12065 0.3048)
			(end 0.67945 0.3048)
			(stroke
				(width 0.1)
				(type default)
			)
			(layer "B.Fab")
		)
		(fp_line
			(start 0.67945 0.3048)
			(end 0.67945 -0.305054)
			(stroke
				(width 0.1)
				(type default)
			)
			(layer "B.Fab")
		)
		(fp_line
			(start -0.120396 0.2794)
			(end 0.12065 0.2794)
			(stroke
				(width 0.1)
				(type default)
			)
			(layer "B.Fab")
		)
		(fp_line
			(start 0.12065 0.2794)
			(end 0.12065 0.3048)
			(stroke
				(width 0.1)
				(type default)
			)
			(layer "B.Fab")
		)
		(fp_line
			(start -0.12065 -0.2794)
			(end -0.12065 -0.3048)
			(stroke
				(width 0.1)
				(type default)
			)
			(layer "B.Fab")
		)
		(fp_line
			(start 0.12065 -0.2794)
			(end -0.12065 -0.2794)
			(stroke
				(width 0.1)
				(type default)
			)
			(layer "B.Fab")
		)
		(fp_line
			(start -0.67945 -0.3048)
			(end -0.67945 0.3048)
			(stroke
				(width 0.1)
				(type default)
			)
			(layer "B.Fab")
		)
		(fp_line
			(start -0.12065 -0.3048)
			(end -0.67945 -0.3048)
			(stroke
				(width 0.1)
				(type default)
			)
			(layer "B.Fab")
		)
		(fp_line
			(start 0.12065 -0.305054)
			(end 0.12065 -0.2794)
			(stroke
				(width 0.1)
				(type default)
			)
			(layer "B.Fab")
		)
		(fp_line
			(start 0.67945 -0.305054)
			(end 0.12065 -0.305054)
			(stroke
				(width 0.1)
				(type default)
			)
			(layer "B.Fab")
		)
		(pad "1" smd circle
			(at 0.40005 0 90)
			(size 0 0)
			(layers "B.Cu" "B.Mask" "B.Paste")
			(net "PVDDIO_P0_VOS3")
		)
		(pad "2" smd circle
			(at -0.40005 0 90)
			(size 0 0)
			(layers "B.Cu" "B.Mask" "B.Paste")
			(net "PVDDIO_P0")
		)
	)
	(footprint ""
		(layer "B.Cu")
		(at 352.846132 -396.393162 -90)
		(property "Reference" "C631"
			(at 0 0 90)
			(layer "B.SilkS")
			(hide yes)
			(effects
				(font
					(size 1.27 1.27)
				)
				(justify mirror)
			)
		)
		(property "Value" ""
			(at 0 0 90)
			(layer "B.Fab")
			(effects
				(font
					(size 1.27 1.27)
				)
				(justify mirror)
			)
		)
		(duplicate_pad_numbers_are_jumpers no)
		(fp_line
			(start -0.299974 0.150114)
			(end 0.299974 0.150114)
			(stroke
				(width 0.1)
				(type default)
			)
			(layer "B.Fab")
		)
		(fp_line
			(start 0.299974 0.150114)
			(end 0.299974 -0.150114)
			(stroke
				(width 0.1)
				(type default)
			)
			(layer "B.Fab")
		)
		(fp_line
			(start -0.299974 -0.150114)
			(end -0.299974 0.150114)
			(stroke
				(width 0.1)
				(type default)
			)
			(layer "B.Fab")
		)
		(fp_line
			(start 0.299974 -0.150114)
			(end -0.299974 -0.150114)
			(stroke
				(width 0.1)
				(type default)
			)
			(layer "B.Fab")
		)
		(pad "1" smd rect
			(at 0.2667 0 90)
			(size 0.3048 0.381)
			(layers "B.Cu" "B.Mask" "B.Paste")
			(net "P0V9_CPU0_RT1_2A")
		)
		(pad "2" smd rect
			(at -0.2667 0 90)
			(size 0.3048 0.381)
			(layers "B.Cu" "B.Mask" "B.Paste")
			(net "GND")
		)
	)
)
